(kicad_pcb
	(version 20241229)
	(generator "pcbnew")
	(generator_version "9.0")
	(general
		(thickness 1.6)
		(legacy_teardrops no)
	)
	(paper "A4")
	(title_block
		(title "LPDDR4 testbed")
		(date "2024-03-26")
		(rev "1.2.2")
		(comment 9 "footprints 54-59 of 66")
	)
	(layers
		(0 "F.Cu" signal)
		(4 "In1.Cu" power)
		(6 "In2.Cu" power)
		(8 "In3.Cu" signal)
		(10 "In4.Cu" signal)
		(2 "B.Cu" signal)
		(9 "F.Adhes" user "F.Adhesive")
		(11 "B.Adhes" user "B.Adhesive")
		(13 "F.Paste" user)
		(15 "B.Paste" user)
		(5 "F.SilkS" user "F.Silkscreen")
		(7 "B.SilkS" user "B.Silkscreen")
		(1 "F.Mask" user)
		(3 "B.Mask" user)
		(17 "Dwgs.User" user "User.Drawings")
		(19 "Cmts.User" user "User.Comments")
		(21 "Eco1.User" user "User.Eco1")
		(23 "Eco2.User" user "User.Eco2")
		(25 "Edge.Cuts" user)
		(27 "Margin" user)
		(31 "F.CrtYd" user "F.Courtyard")
		(29 "B.CrtYd" user "B.Courtyard")
		(35 "F.Fab" user)
		(33 "B.Fab" user)
	)
	(footprint "antmicro-footprints:C_0201"
		(layer "B.Cu")
		(at 153.375 82.55 -90)
		(descr "Capacitor SMD 0201")
		(tags "capacitor SMD 0201")
		(property "Reference" "C8"
			(at 0.6 -0.3 90)
			(layer "B.SilkS")
			(effects
				(font
					(size 0.7 0.7)
					(thickness 0.15)
				)
				(justify left bottom mirror)
			)
		)
		(property "Value" "C_100n_0201"
			(at 0 -1.4 90)
			(layer "B.Fab")
			(effects
				(font
					(size 0.7 0.7)
					(thickness 0.15)
				)
				(justify left bottom mirror)
			)
		)
		(property "Description" " "
			(at 0 0 270)
			(layer "F.Fab")
			(hide yes)
			(effects
				(font
					(size 1.27 1.27)
					(thickness 0.15)
				)
			)
		)
		(property "Author" "Antmicro"
			(at 70.825 235.925 0)
			(layer "B.Fab")
			(hide yes)
			(effects
				(font
					(size 1 1)
					(thickness 0.15)
				)
				(justify mirror)
			)
		)
		(property "Dielectric" ""
			(at 70.825 235.925 0)
			(layer "B.Fab")
			(hide yes)
			(effects
				(font
					(size 1 1)
					(thickness 0.15)
				)
				(justify mirror)
			)
		)
		(property "License" "Apache-2.0"
			(at 70.825 235.925 0)
			(layer "B.Fab")
			(hide yes)
			(effects
				(font
					(size 1 1)
					(thickness 0.15)
				)
				(justify mirror)
			)
		)
		(property "MPN" "CC0201KRX6S5BB104"
			(at 70.825 235.925 0)
			(layer "B.Fab")
			(hide yes)
			(effects
				(font
					(size 1 1)
					(thickness 0.15)
				)
				(justify mirror)
			)
		)
		(property "Manufacturer" "YAGEO"
			(at 70.825 235.925 0)
			(layer "B.Fab")
			(hide yes)
			(effects
				(font
					(size 1 1)
					(thickness 0.15)
				)
				(justify mirror)
			)
		)
		(property "Val" "100n"
			(at 70.825 235.925 0)
			(layer "B.Fab")
			(hide yes)
			(effects
				(font
					(size 1 1)
					(thickness 0.15)
				)
				(justify mirror)
			)
		)
		(property "Voltage" ""
			(at 70.825 235.925 0)
			(layer "B.Fab")
			(hide yes)
			(effects
				(font
					(size 1 1)
					(thickness 0.15)
				)
				(justify mirror)
			)
		)
		(sheetname "LPDDR4")
		(sheetfile "lpddr4.kicad_sch")
		(attr smd)
		(fp_rect
			(start -0.72 0.38)
			(end 0.72 -0.38)
			(stroke
				(width 0.05)
				(type solid)
			)
			(fill no)
			(layer "B.CrtYd")
		)
		(fp_rect
			(start 0.3 -0.15)
			(end -0.301 0.149)
			(stroke
				(width 0.15)
				(type solid)
			)
			(fill no)
			(layer "B.Fab")
		)
		(pad "" smd roundrect
			(at -0.349 0.002 270)
			(size 0.318 0.36)
			(layers "B.Paste")
			(roundrect_rratio 0.25)
		)
		(pad "" smd roundrect
			(at 0.341 0.002 270)
			(size 0.318 0.36)
			(layers "B.Paste")
			(roundrect_rratio 0.25)
		)
		(pad "1" smd roundrect
			(at -0.321 0.002 270)
			(size 0.46 0.4)
			(layers "B.Cu" "B.Mask")
			(roundrect_rratio 0.25)
			(net 36 "GND")
			(pintype "passive")
		)
		(pad "2" smd roundrect
			(at 0.32 0.002 270)
			(size 0.46 0.4)
			(layers "B.Cu" "B.Mask")
			(roundrect_rratio 0.25)
			(net 189 "VDDQ")
			(pintype "passive")
		)
	)
	(footprint "antmicro-footprints:C_0201"
		(layer "B.Cu")
		(at 149.375 91 -90)
		(descr "Capacitor SMD 0201")
		(tags "capacitor SMD 0201")
		(property "Reference" "C5"
			(at -0.75 0.4 90)
			(layer "B.SilkS")
			(effects
				(font
					(size 0.7 0.7)
					(thickness 0.15)
				)
				(justify left bottom mirror)
			)
		)
		(property "Value" "C_100n_0201"
			(at 0 -1.4 90)
			(layer "B.Fab")
			(effects
				(font
					(size 0.7 0.7)
					(thickness 0.15)
				)
				(justify left bottom mirror)
			)
		)
		(property "Description" " "
			(at 0 0 270)
			(layer "F.Fab")
			(hide yes)
			(effects
				(font
					(size 1.27 1.27)
					(thickness 0.15)
				)
			)
		)
		(property "Author" "Antmicro"
			(at 58.375 240.375 0)
			(layer "B.Fab")
			(hide yes)
			(effects
				(font
					(size 1 1)
					(thickness 0.15)
				)
				(justify mirror)
			)
		)
		(property "Dielectric" ""
			(at 58.375 240.375 0)
			(layer "B.Fab")
			(hide yes)
			(effects
				(font
					(size 1 1)
					(thickness 0.15)
				)
				(justify mirror)
			)
		)
		(property "License" "Apache-2.0"
			(at 58.375 240.375 0)
			(layer "B.Fab")
			(hide yes)
			(effects
				(font
					(size 1 1)
					(thickness 0.15)
				)
				(justify mirror)
			)
		)
		(property "MPN" "CC0201KRX6S5BB104"
			(at 58.375 240.375 0)
			(layer "B.Fab")
			(hide yes)
			(effects
				(font
					(size 1 1)
					(thickness 0.15)
				)
				(justify mirror)
			)
		)
		(property "Manufacturer" "YAGEO"
			(at 58.375 240.375 0)
			(layer "B.Fab")
			(hide yes)
			(effects
				(font
					(size 1 1)
					(thickness 0.15)
				)
				(justify mirror)
			)
		)
		(property "Val" "100n"
			(at 58.375 240.375 0)
			(layer "B.Fab")
			(hide yes)
			(effects
				(font
					(size 1 1)
					(thickness 0.15)
				)
				(justify mirror)
			)
		)
		(property "Voltage" ""
			(at 58.375 240.375 0)
			(layer "B.Fab")
			(hide yes)
			(effects
				(font
					(size 1 1)
					(thickness 0.15)
				)
				(justify mirror)
			)
		)
		(sheetname "LPDDR4")
		(sheetfile "lpddr4.kicad_sch")
		(attr smd)
		(fp_rect
			(start -0.72 0.38)
			(end 0.72 -0.38)
			(stroke
				(width 0.05)
				(type solid)
			)
			(fill no)
			(layer "B.CrtYd")
		)
		(fp_rect
			(start 0.3 -0.15)
			(end -0.301 0.149)
			(stroke
				(width 0.15)
				(type solid)
			)
			(fill no)
			(layer "B.Fab")
		)
		(pad "" smd roundrect
			(at -0.349 0.002 270)
			(size 0.318 0.36)
			(layers "B.Paste")
			(roundrect_rratio 0.25)
		)
		(pad "" smd roundrect
			(at 0.341 0.002 270)
			(size 0.318 0.36)
			(layers "B.Paste")
			(roundrect_rratio 0.25)
		)
		(pad "1" smd roundrect
			(at -0.321 0.002 270)
			(size 0.46 0.4)
			(layers "B.Cu" "B.Mask")
			(roundrect_rratio 0.25)
			(net 36 "GND")
			(pintype "passive")
		)
		(pad "2" smd roundrect
			(at 0.32 0.002 270)
			(size 0.46 0.4)
			(layers "B.Cu" "B.Mask")
			(roundrect_rratio 0.25)
			(net 189 "VDDQ")
			(pintype "passive")
		)
	)
	(footprint "antmicro-footprints:C_0201"
		(layer "B.Cu")
		(at 149.375 81.45 -90)
		(descr "Capacitor SMD 0201")
		(tags "capacitor SMD 0201")
		(property "Reference" "C16"
			(at -1.2 -1.2 90)
			(layer "B.SilkS")
			(effects
				(font
					(size 0.7 0.7)
					(thickness 0.15)
				)
				(justify left bottom mirror)
			)
		)
		(property "Value" "C_100n_0201"
			(at 0 -1.4 90)
			(layer "B.Fab")
			(effects
				(font
					(size 0.7 0.7)
					(thickness 0.15)
				)
				(justify left bottom mirror)
			)
		)
		(property "Description" " "
			(at 0 0 270)
			(layer "F.Fab")
			(hide yes)
			(effects
				(font
					(size 1.27 1.27)
					(thickness 0.15)
				)
			)
		)
		(property "Author" "Antmicro"
			(at 67.925 230.825 0)
			(layer "B.Fab")
			(hide yes)
			(effects
				(font
					(size 1 1)
					(thickness 0.15)
				)
				(justify mirror)
			)
		)
		(property "Dielectric" ""
			(at 67.925 230.825 0)
			(layer "B.Fab")
			(hide yes)
			(effects
				(font
					(size 1 1)
					(thickness 0.15)
				)
				(justify mirror)
			)
		)
		(property "License" "Apache-2.0"
			(at 67.925 230.825 0)
			(layer "B.Fab")
			(hide yes)
			(effects
				(font
					(size 1 1)
					(thickness 0.15)
				)
				(justify mirror)
			)
		)
		(property "MPN" "CC0201KRX6S5BB104"
			(at 67.925 230.825 0)
			(layer "B.Fab")
			(hide yes)
			(effects
				(font
					(size 1 1)
					(thickness 0.15)
				)
				(justify mirror)
			)
		)
		(property "Manufacturer" "YAGEO"
			(at 67.925 230.825 0)
			(layer "B.Fab")
			(hide yes)
			(effects
				(font
					(size 1 1)
					(thickness 0.15)
				)
				(justify mirror)
			)
		)
		(property "Val" "100n"
			(at 67.925 230.825 0)
			(layer "B.Fab")
			(hide yes)
			(effects
				(font
					(size 1 1)
					(thickness 0.15)
				)
				(justify mirror)
			)
		)
		(property "Voltage" ""
			(at 67.925 230.825 0)
			(layer "B.Fab")
			(hide yes)
			(effects
				(font
					(size 1 1)
					(thickness 0.15)
				)
				(justify mirror)
			)
		)
		(sheetname "LPDDR4")
		(sheetfile "lpddr4.kicad_sch")
		(attr smd)
		(fp_rect
			(start -0.72 0.38)
			(end 0.72 -0.38)
			(stroke
				(width 0.05)
				(type solid)
			)
			(fill no)
			(layer "B.CrtYd")
		)
		(fp_rect
			(start 0.3 -0.15)
			(end -0.301 0.149)
			(stroke
				(width 0.15)
				(type solid)
			)
			(fill no)
			(layer "B.Fab")
		)
		(pad "" smd roundrect
			(at -0.349 0.002 270)
			(size 0.318 0.36)
			(layers "B.Paste")
			(roundrect_rratio 0.25)
		)
		(pad "" smd roundrect
			(at 0.341 0.002 270)
			(size 0.318 0.36)
			(layers "B.Paste")
			(roundrect_rratio 0.25)
		)
		(pad "1" smd roundrect
			(at -0.321 0.002 270)
			(size 0.46 0.4)
			(layers "B.Cu" "B.Mask")
			(roundrect_rratio 0.25)
			(net 36 "GND")
			(pintype "passive")
		)
		(pad "2" smd roundrect
			(at 0.32 0.002 270)
			(size 0.46 0.4)
			(layers "B.Cu" "B.Mask")
			(roundrect_rratio 0.25)
			(net 189 "VDDQ")
			(pintype "passive")
		)
	)
	(footprint "antmicro-footprints:C_0201"
		(layer "B.Cu")
		(at 149.375 92.5 -90)
		(descr "Capacitor SMD 0201")
		(tags "capacitor SMD 0201")
		(property "Reference" "C17"
			(at -0.85 -1.3 90)
			(layer "B.SilkS")
			(effects
				(font
					(size 0.7 0.7)
					(thickness 0.15)
				)
				(justify left bottom mirror)
			)
		)
		(property "Value" "C_100n_0201"
			(at 0 -1.4 90)
			(layer "B.Fab")
			(effects
				(font
					(size 0.7 0.7)
					(thickness 0.15)
				)
				(justify left bottom mirror)
			)
		)
		(property "Description" " "
			(at 0 0 270)
			(layer "F.Fab")
			(hide yes)
			(effects
				(font
					(size 1.27 1.27)
					(thickness 0.15)
				)
			)
		)
		(property "Author" "Antmicro"
			(at 56.875 241.875 0)
			(layer "B.Fab")
			(hide yes)
			(effects
				(font
					(size 1 1)
					(thickness 0.15)
				)
				(justify mirror)
			)
		)
		(property "Dielectric" ""
			(at 56.875 241.875 0)
			(layer "B.Fab")
			(hide yes)
			(effects
				(font
					(size 1 1)
					(thickness 0.15)
				)
				(justify mirror)
			)
		)
		(property "License" "Apache-2.0"
			(at 56.875 241.875 0)
			(layer "B.Fab")
			(hide yes)
			(effects
				(font
					(size 1 1)
					(thickness 0.15)
				)
				(justify mirror)
			)
		)
		(property "MPN" "CC0201KRX6S5BB104"
			(at 56.875 241.875 0)
			(layer "B.Fab")
			(hide yes)
			(effects
				(font
					(size 1 1)
					(thickness 0.15)
				)
				(justify mirror)
			)
		)
		(property "Manufacturer" "YAGEO"
			(at 56.875 241.875 0)
			(layer "B.Fab")
			(hide yes)
			(effects
				(font
					(size 1 1)
					(thickness 0.15)
				)
				(justify mirror)
			)
		)
		(property "Val" "100n"
			(at 56.875 241.875 0)
			(layer "B.Fab")
			(hide yes)
			(effects
				(font
					(size 1 1)
					(thickness 0.15)
				)
				(justify mirror)
			)
		)
		(property "Voltage" ""
			(at 56.875 241.875 0)
			(layer "B.Fab")
			(hide yes)
			(effects
				(font
					(size 1 1)
					(thickness 0.15)
				)
				(justify mirror)
			)
		)
		(sheetname "LPDDR4")
		(sheetfile "lpddr4.kicad_sch")
		(attr smd)
		(fp_rect
			(start -0.72 0.38)
			(end 0.72 -0.38)
			(stroke
				(width 0.05)
				(type solid)
			)
			(fill no)
			(layer "B.CrtYd")
		)
		(fp_rect
			(start 0.3 -0.15)
			(end -0.301 0.149)
			(stroke
				(width 0.15)
				(type solid)
			)
			(fill no)
			(layer "B.Fab")
		)
		(pad "" smd roundrect
			(at -0.349 0.002 270)
			(size 0.318 0.36)
			(layers "B.Paste")
			(roundrect_rratio 0.25)
		)
		(pad "" smd roundrect
			(at 0.341 0.002 270)
			(size 0.318 0.36)
			(layers "B.Paste")
			(roundrect_rratio 0.25)
		)
		(pad "1" smd roundrect
			(at -0.321 0.002 270)
			(size 0.46 0.4)
			(layers "B.Cu" "B.Mask")
			(roundrect_rratio 0.25)
			(net 36 "GND")
			(pintype "passive")
		)
		(pad "2" smd roundrect
			(at 0.32 0.002 270)
			(size 0.46 0.4)
			(layers "B.Cu" "B.Mask")
			(roundrect_rratio 0.25)
			(net 189 "VDDQ")
			(pintype "passive")
		)
	)
	(footprint "antmicro-footprints:C_0201"
		(layer "B.Cu")
		(at 146.325 83.15 90)
		(descr "Capacitor SMD 0201")
		(tags "capacitor SMD 0201")
		(property "Reference" "C19"
			(at -1.1 -0.45 90)
			(layer "B.SilkS")
			(effects
				(font
					(size 0.7 0.7)
					(thickness 0.15)
				)
				(justify right bottom mirror)
			)
		)
		(property "Value" "C_100n_0201"
			(at 0 -1.4 90)
			(layer "B.Fab")
			(effects
				(font
					(size 0.7 0.7)
					(thickness 0.15)
				)
				(justify right bottom mirror)
			)
		)
		(property "Description" " "
			(at 0 0 90)
			(layer "F.Fab")
			(hide yes)
			(effects
				(font
					(size 1.27 1.27)
					(thickness 0.15)
				)
			)
		)
		(property "Author" "Antmicro"
			(at 229.475 -63.175 0)
			(layer "B.Fab")
			(hide yes)
			(effects
				(font
					(size 1 1)
					(thickness 0.15)
				)
				(justify mirror)
			)
		)
		(property "Dielectric" ""
			(at 229.475 -63.175 0)
			(layer "B.Fab")
			(hide yes)
			(effects
				(font
					(size 1 1)
					(thickness 0.15)
				)
				(justify mirror)
			)
		)
		(property "License" "Apache-2.0"
			(at 229.475 -63.175 0)
			(layer "B.Fab")
			(hide yes)
			(effects
				(font
					(size 1 1)
					(thickness 0.15)
				)
				(justify mirror)
			)
		)
		(property "MPN" "CC0201KRX6S5BB104"
			(at 229.475 -63.175 0)
			(layer "B.Fab")
			(hide yes)
			(effects
				(font
					(size 1 1)
					(thickness 0.15)
				)
				(justify mirror)
			)
		)
		(property "Manufacturer" "YAGEO"
			(at 229.475 -63.175 0)
			(layer "B.Fab")
			(hide yes)
			(effects
				(font
					(size 1 1)
					(thickness 0.15)
				)
				(justify mirror)
			)
		)
		(property "Val" "100n"
			(at 229.475 -63.175 0)
			(layer "B.Fab")
			(hide yes)
			(effects
				(font
					(size 1 1)
					(thickness 0.15)
				)
				(justify mirror)
			)
		)
		(property "Voltage" ""
			(at 229.475 -63.175 0)
			(layer "B.Fab")
			(hide yes)
			(effects
				(font
					(size 1 1)
					(thickness 0.15)
				)
				(justify mirror)
			)
		)
		(sheetname "LPDDR4")
		(sheetfile "lpddr4.kicad_sch")
		(attr smd)
		(fp_rect
			(start -0.72 0.38)
			(end 0.72 -0.38)
			(stroke
				(width 0.05)
				(type solid)
			)
			(fill no)
			(layer "B.CrtYd")
		)
		(fp_rect
			(start 0.3 -0.15)
			(end -0.301 0.149)
			(stroke
				(width 0.15)
				(type solid)
			)
			(fill no)
			(layer "B.Fab")
		)
		(pad "" smd roundrect
			(at -0.349 0.002 90)
			(size 0.318 0.36)
			(layers "B.Paste")
			(roundrect_rratio 0.25)
		)
		(pad "" smd roundrect
			(at 0.341 0.002 90)
			(size 0.318 0.36)
			(layers "B.Paste")
			(roundrect_rratio 0.25)
		)
		(pad "1" smd roundrect
			(at -0.321 0.002 90)
			(size 0.46 0.4)
			(layers "B.Cu" "B.Mask")
			(roundrect_rratio 0.25)
			(net 36 "GND")
			(pintype "passive")
		)
		(pad "2" smd roundrect
			(at 0.32 0.002 90)
			(size 0.46 0.4)
			(layers "B.Cu" "B.Mask")
			(roundrect_rratio 0.25)
			(net 189 "VDDQ")
			(pintype "passive")
		)
	)
	(footprint "antmicro-footprints:C_0201"
		(layer "B.Cu")
		(at 149.375 87.65 -90)
		(descr "Capacitor SMD 0201")
		(tags "capacitor SMD 0201")
		(property "Reference" "C23"
			(at -0.9 0.5 90)
			(layer "B.SilkS")
			(effects
				(font
					(size 0.7 0.7)
					(thickness 0.15)
				)
				(justify left bottom mirror)
			)
		)
		(property "Value" "C_100n_0201"
			(at 0 -1.4 90)
			(layer "B.Fab")
			(effects
				(font
					(size 0.7 0.7)
					(thickness 0.15)
				)
				(justify left bottom mirror)
			)
		)
		(property "Description" " "
			(at 0 0 270)
			(layer "F.Fab")
			(hide yes)
			(effects
				(font
					(size 1.27 1.27)
					(thickness 0.15)
				)
			)
		)
		(property "Author" "Antmicro"
			(at 61.725 237.025 0)
			(layer "B.Fab")
			(hide yes)
			(effects
				(font
					(size 1 1)
					(thickness 0.15)
				)
				(justify mirror)
			)
		)
		(property "Dielectric" ""
			(at 61.725 237.025 0)
			(layer "B.Fab")
			(hide yes)
			(effects
				(font
					(size 1 1)
					(thickness 0.15)
				)
				(justify mirror)
			)
		)
		(property "License" "Apache-2.0"
			(at 61.725 237.025 0)
			(layer "B.Fab")
			(hide yes)
			(effects
				(font
					(size 1 1)
					(thickness 0.15)
				)
				(justify mirror)
			)
		)
		(property "MPN" "CC0201KRX6S5BB104"
			(at 61.725 237.025 0)
			(layer "B.Fab")
			(hide yes)
			(effects
				(font
					(size 1 1)
					(thickness 0.15)
				)
				(justify mirror)
			)
		)
		(property "Manufacturer" "YAGEO"
			(at 61.725 237.025 0)
			(layer "B.Fab")
			(hide yes)
			(effects
				(font
					(size 1 1)
					(thickness 0.15)
				)
				(justify mirror)
			)
		)
		(property "Val" "100n"
			(at 61.725 237.025 0)
			(layer "B.Fab")
			(hide yes)
			(effects
				(font
					(size 1 1)
					(thickness 0.15)
				)
				(justify mirror)
			)
		)
		(property "Voltage" ""
			(at 61.725 237.025 0)
			(layer "B.Fab")
			(hide yes)
			(effects
				(font
					(size 1 1)
					(thickness 0.15)
				)
				(justify mirror)
			)
		)
		(sheetname "LPDDR4")
		(sheetfile "lpddr4.kicad_sch")
		(attr smd)
		(fp_rect
			(start -0.72 0.38)
			(end 0.72 -0.38)
			(stroke
				(width 0.05)
				(type solid)
			)
			(fill no)
			(layer "B.CrtYd")
		)
		(fp_rect
			(start 0.3 -0.15)
			(end -0.301 0.149)
			(stroke
				(width 0.15)
				(type solid)
			)
			(fill no)
			(layer "B.Fab")
		)
		(pad "" smd roundrect
			(at -0.349 0.002 270)
			(size 0.318 0.36)
			(layers "B.Paste")
			(roundrect_rratio 0.25)
		)
		(pad "" smd roundrect
			(at 0.341 0.002 270)
			(size 0.318 0.36)
			(layers "B.Paste")
			(roundrect_rratio 0.25)
		)
		(pad "1" smd roundrect
			(at -0.321 0.002 270)
			(size 0.46 0.4)
			(layers "B.Cu" "B.Mask")
			(roundrect_rratio 0.25)
			(net 36 "GND")
			(pintype "passive")
		)
		(pad "2" smd roundrect
			(at 0.32 0.002 270)
			(size 0.46 0.4)
			(layers "B.Cu" "B.Mask")
			(roundrect_rratio 0.25)
			(net 188 "VDD2")
			(pintype "passive")
		)
	)
)
